# S9S_MB_2U (Grand Teton) — schematic netlist excerpt (pin names and nets, part order shuffled) for the footprints in the layout excerpt that follows; sources: Cadence DE-HDL packaged netlist, KiCad conversion of 03242023_DA0F0TMBIJ0_F0T_Motherboard_J_brd_V01_OCP.brd

PC446  Q_CAP  100NF 50V 10% X7R  pkg C0402  page 293 : A = SW_PVCCINFAON_CPU1_BOOT1_R ; B = SW_PVCCINFAON_CPU1_BOOTR1

JP4003  CONN3_210HP1030BR1  CONN3_210-HP1-030BR1 IO  pkg HEADER1X3XG  page 301
  \1\  = NC
  \2\  = PDB_PRSNT_N
  \3\  = GND

(kicad_pcb
	(version 20260206)
	(generator "pcbnew")
	(generator_version "10.0")
	(general
		(thickness 1.6)
		(legacy_teardrops no)
	)
	(paper "A4")
	(title_block
		(title "03242023_DA0F0TMBIJ0_F0T_Motherboard_J_brd_V01_OCP.brd")
		(comment 1 "Grand Teton / footprints 420-421 of 6105")
	)
	(layers
		(0 "F.Cu" signal "TOP")
		(4 "In1.Cu" signal "GND")
		(6 "In2.Cu" signal "IN1")
		(8 "In3.Cu" signal "GND1")
		(10 "In4.Cu" signal "IN2")
		(12 "In5.Cu" signal "GND2")
		(14 "In6.Cu" signal "IN3")
		(16 "In7.Cu" signal "GND3")
		(18 "In8.Cu" signal "VCC")
		(20 "In9.Cu" signal "VCC1")
		(22 "In10.Cu" signal "GND4")
		(24 "In11.Cu" signal "IN4")
		(26 "In12.Cu" signal "GND5")
		(28 "In13.Cu" signal "IN5")
		(30 "In14.Cu" signal "GND6")
		(32 "In15.Cu" signal "IN6")
		(34 "In16.Cu" signal "GND7")
		(2 "B.Cu" signal "BOTTOM")
		(9 "F.Adhes" user "F.Adhesive")
		(11 "B.Adhes" user "B.Adhesive")
		(13 "F.Paste" user "Package Geometry/Pastemask Top")
		(15 "B.Paste" user "Package Geometry/Pastemask Bottom")
		(5 "F.SilkS" user "Ref Des/Silkscreen Top")
		(7 "B.SilkS" user "Ref Des/Silkscreen Bottom")
		(1 "F.Mask" user "Board Geometry/Soldermask Top")
		(3 "B.Mask" user "Board Geometry/Soldermask Bottom")
		(17 "Dwgs.User" user "User.Drawings")
		(19 "Cmts.User" user "User.Comments")
		(21 "Eco1.User" user "User.Eco1")
		(23 "Eco2.User" user "User.Eco2")
		(25 "Edge.Cuts" user "Board Geometry/Outline")
		(27 "Margin" user)
		(31 "F.CrtYd" user "Package Geometry/Place Bound Top")
		(29 "B.CrtYd" user "Package Geometry/Place Bound Bottom")
		(35 "F.Fab" user "Ref Des/Assembly Top")
		(33 "B.Fab" user "Ref Des/Assembly Bottom")
	)
	(footprint ""
		(layer "F.Cu")
		(at 50.437542 -158.211266)
		(property "Reference" "PC446"
			(at 0 0 0)
			(layer "F.SilkS")
			(hide yes)
			(effects
				(font
					(size 1.27 1.27)
				)
			)
		)
		(property "Value" ""
			(at 0 0 0)
			(layer "F.Fab")
			(effects
				(font
					(size 1.27 1.27)
				)
			)
		)
		(duplicate_pad_numbers_are_jumpers no)
		(fp_line
			(start -0.7874 -0.4064)
			(end 0.7874 -0.4064)
			(stroke
				(width 0.1524)
				(type default)
			)
			(layer "F.SilkS")
		)
		(fp_line
			(start -0.7874 0.4064)
			(end -0.7874 -0.4064)
			(stroke
				(width 0.1524)
				(type default)
			)
			(layer "F.SilkS")
		)
		(fp_line
			(start 0.7874 -0.4064)
			(end 0.7874 0.4064)
			(stroke
				(width 0.1524)
				(type default)
			)
			(layer "F.SilkS")
		)
		(fp_line
			(start 0.7874 0.4064)
			(end -0.7874 0.4064)
			(stroke
				(width 0.1524)
				(type default)
			)
			(layer "F.SilkS")
		)
		(fp_line
			(start -0.67945 -0.305054)
			(end -0.12065 -0.305054)
			(stroke
				(width 0.1)
				(type default)
			)
			(layer "F.Fab")
		)
		(fp_line
			(start -0.67945 0.3048)
			(end -0.67945 -0.305054)
			(stroke
				(width 0.1)
				(type default)
			)
			(layer "F.Fab")
		)
		(fp_line
			(start -0.12065 -0.305054)
			(end -0.12065 -0.2794)
			(stroke
				(width 0.1)
				(type default)
			)
			(layer "F.Fab")
		)
		(fp_line
			(start -0.12065 -0.2794)
			(end 0.12065 -0.2794)
			(stroke
				(width 0.1)
				(type default)
			)
			(layer "F.Fab")
		)
		(fp_line
			(start -0.12065 0.2794)
			(end -0.12065 0.3048)
			(stroke
				(width 0.1)
				(type default)
			)
			(layer "F.Fab")
		)
		(fp_line
			(start -0.12065 0.3048)
			(end -0.67945 0.3048)
			(stroke
				(width 0.1)
				(type default)
			)
			(layer "F.Fab")
		)
		(fp_line
			(start 0.120396 0.2794)
			(end -0.12065 0.2794)
			(stroke
				(width 0.1)
				(type default)
			)
			(layer "F.Fab")
		)
		(fp_line
			(start 0.120396 0.3048)
			(end 0.120396 0.2794)
			(stroke
				(width 0.1)
				(type default)
			)
			(layer "F.Fab")
		)
		(fp_line
			(start 0.12065 -0.3048)
			(end 0.67945 -0.3048)
			(stroke
				(width 0.1)
				(type default)
			)
			(layer "F.Fab")
		)
		(fp_line
			(start 0.12065 -0.2794)
			(end 0.12065 -0.3048)
			(stroke
				(width 0.1)
				(type default)
			)
			(layer "F.Fab")
		)
		(fp_line
			(start 0.67945 -0.3048)
			(end 0.67945 0.3048)
			(stroke
				(width 0.1)
				(type default)
			)
			(layer "F.Fab")
		)
		(fp_line
			(start 0.67945 0.3048)
			(end 0.120396 0.3048)
			(stroke
				(width 0.1)
				(type default)
			)
			(layer "F.Fab")
		)
		(pad "1" smd circle
			(at -0.40005 0)
			(size 0 0)
			(layers "F.Cu" "F.Mask" "F.Paste")
			(net "SW_PVCCINFAON_CPU1_BOOT1_R")
		)
		(pad "2" smd circle
			(at 0.40005 0)
			(size 0 0)
			(layers "F.Cu" "F.Mask" "F.Paste")
			(net "SW_PVCCINFAON_CPU1_BOOTR1")
		)
	)
	(footprint ""
		(layer "F.Cu")
		(at 174.879 -411.9626)
		(property "Reference" "JP4003"
			(at 2.060448 3.252724 90)
			(unlocked yes)
			(layer "F.SilkS")
			(effects
				(font
					(size 0.7874 0.5842)
					(thickness 0.1524)
				)
				(justify left)
			)
		)
		(property "Value" ""
			(at 0 0 0)
			(layer "F.Fab")
			(effects
				(font
					(size 1.27 1.27)
				)
			)
		)
		(duplicate_pad_numbers_are_jumpers no)
		(fp_line
			(start -1.249934 -1.320038)
			(end 1.249934 -1.320038)
			(stroke
				(width 0.1524)
				(type default)
			)
			(layer "F.SilkS")
		)
		(fp_line
			(start -1.249934 6.400038)
			(end -1.249934 -1.320038)
			(stroke
				(width 0.1524)
				(type default)
			)
			(layer "F.SilkS")
		)
		(fp_line
			(start 1.249934 -1.320038)
			(end 1.249934 6.400038)
			(stroke
				(width 0.1524)
				(type default)
			)
			(layer "F.SilkS")
		)
		(fp_line
			(start 1.249934 6.400038)
			(end -1.249934 6.400038)
			(stroke
				(width 0.1524)
				(type default)
			)
			(layer "F.SilkS")
		)
		(fp_poly
			(pts
				(xy -1.452372 0) (xy -2.5654 0.556514) (xy -2.5654 -0.556514)
			)
			(stroke
				(width 0)
				(type default)
			)
			(fill yes)
			(layer "F.SilkS")
		)
		(fp_line
			(start -1.249934 -1.320038)
			(end 1.249934 -1.320038)
			(stroke
				(width 0.1)
				(type default)
			)
			(layer "F.Fab")
		)
		(fp_line
			(start -1.249934 6.400038)
			(end -1.249934 -1.320038)
			(stroke
				(width 0.1)
				(type default)
			)
			(layer "F.Fab")
		)
		(fp_line
			(start 1.249934 -1.320038)
			(end 1.249934 6.400038)
			(stroke
				(width 0.1)
				(type default)
			)
			(layer "F.Fab")
		)
		(fp_line
			(start 1.249934 6.400038)
			(end -1.249934 6.400038)
			(stroke
				(width 0.1)
				(type default)
			)
			(layer "F.Fab")
		)
		(fp_poly
			(pts
				(xy -2.5654 -0.556514) (xy -1.452372 0) (xy -2.5654 0.556514)
			)
			(stroke
				(width 0)
				(type default)
			)
			(fill yes)
			(layer "F.Fab")
		)
		(fp_text user "3"
			(at -1.909572 5.30225 180)
			(unlocked yes)
			(layer "F.SilkS")
			(effects
				(font
					(size 0.7874 0.5842)
					(thickness 0.1524)
				)
			)
		)
		(fp_text user "3"
			(at -1.502156 5.17271 180)
			(unlocked yes)
			(layer "B.SilkS")
			(effects
				(font
					(size 0.7874 0.5842)
					(thickness 0.1524)
				)
				(justify mirror)
			)
		)
		(fp_text user "1"
			(at -1.425956 -0.14351 180)
			(unlocked yes)
			(layer "B.SilkS")
			(effects
				(font
					(size 0.7874 0.5842)
					(thickness 0.1524)
				)
				(justify mirror)
			)
		)
		(fp_text user "3"
			(at -1.1557 5.18287 0)
			(unlocked yes)
			(layer "B.Fab")
			(effects
				(font
					(size 0.7874 0.5842)
					(thickness 0.1524)
				)
				(justify mirror)
			)
		)
		(fp_text user "1"
			(at -1.143 0.02667 0)
			(unlocked yes)
			(layer "B.Fab")
			(effects
				(font
					(size 0.7874 0.5842)
					(thickness 0.1524)
				)
				(justify mirror)
			)
		)
		(fp_text user "3"
			(at -1.778 5.13207 0)
			(unlocked yes)
			(layer "F.Fab")
			(effects
				(font
					(size 0.7874 0.5842)
					(thickness 0.1524)
				)
			)
		)
		(pad "1" thru_hole rect
			(at 0 0)
			(size 1.5494 1.5494)
			(drill 1.0414)
			(layers "*.Cu" "*.Mask")
			(remove_unused_layers no)
			(net "Net_1915")
			(clearance 0)
			(padstack
				(mode front_inner_back)
				(layer "Inner"
					(shape circle)
					(size 1.5494 1.5494)
					(clearance 0)
				)
				(layer "B.Cu"
					(shape rect)
					(size 1.5494 1.5494)
					(clearance 0)
				)
			)
		)
		(pad "2" thru_hole circle
			(at 0 2.54)
			(size 1.5494 1.5494)
			(drill 1.0414)
			(layers "*.Cu" "*.Mask")
			(remove_unused_layers no)
			(net "PDB_PRSNT_N")
			(clearance 0)
		)
		(pad "3" thru_hole circle
			(at 0 5.08)
			(size 1.5494 1.5494)
			(drill 1.0414)
			(layers "*.Cu" "*.Mask")
			(remove_unused_layers no)
			(net "GND")
			(clearance 0)
		)
	)
)
